(kicad_pcb
	(version 20221018)
	(generator pcbnew)
	(general
    (thickness 1.518)
  )
	(paper "A4")
	(title_block
    (title "Kria K26 Devboard")
    (date "2024-03-26")
    (rev "1.2.5")
    (comment 1 "www.antmicro.com")
    (comment 2 "Antmicro Ltd.")
		(comment 9 "footprints 441-441 of 660")
	)
	(layers
    (0 "F.Cu" mixed)
    (1 "In1.Cu" power)
    (2 "In2.Cu" mixed)
    (3 "In3.Cu" power)
    (4 "In4.Cu" mixed)
    (5 "In5.Cu" power)
    (6 "In6.Cu" mixed)
    (31 "B.Cu" power)
    (32 "B.Adhes" user "B.Adhesive")
    (33 "F.Adhes" user "F.Adhesive")
    (34 "B.Paste" user)
    (35 "F.Paste" user)
    (36 "B.SilkS" user "B.Silkscreen")
    (37 "F.SilkS" user "F.Silkscreen")
    (38 "B.Mask" user)
    (39 "F.Mask" user)
    (40 "Dwgs.User" user "User.Drawings")
    (41 "Cmts.User" user "User.Comments")
    (42 "Eco1.User" user "User.Eco1")
    (43 "Eco2.User" user "User.Eco2")
    (44 "Edge.Cuts" user)
    (45 "Margin" user)
    (46 "B.CrtYd" user "B.Courtyard")
    (47 "F.CrtYd" user "F.Courtyard")
    (48 "B.Fab" user)
    (49 "F.Fab" user)
  )
	(footprint "kria-k26-devboard-footprints:Bus_M.2_Socket_Key_E_TE_1-2199119-6" (layer "B.Cu")
    (at 128.52 122.02 90)
    (property "Author" "Antmicro")
    (property "License" "Apache-2.0")
    (property "MPN" "2199119-6")
    (property "Manufacturer" "TE Connectivity")
    (property "Sheetfile" "pcie-m2-key-e.kicad_sch")
    (property "Sheetname" "PCIE M2 key E ")
    (property "ki_description" "Key E, PCI connector")
    (property "ki_keywords" "HORIZONTAL, SMT, PCIE, CONNECTOR")
    (attr smd)
    (fp_text reference "J12" (at 20.781 0.78) (layer "B.SilkS")
        (effects (font (size 0.7 0.7) (thickness 0.15)) (justify left bottom mirror))
    )
    (fp_text value "Bus_M.2_2199119-6" (at -2 -9.6 270) (layer "B.Fab") hide
        (effects (font (size 0.7 0.7) (thickness 0.15)) (justify left bottom mirror))
    )
    (fp_text user "${REFERENCE}" (at -2 -11 270) (layer "B.Fab") hide
        (effects (font (size 0.7 0.7) (thickness 0.15)) (justify left bottom mirror))
    )
    (fp_text user "License: Apache-2.0" (at -1.95 -13.8 270) (layer "B.Fab") hide
        (effects (font (size 0.7 0.7) (thickness 0.15)) (justify left bottom mirror))
    )
    (fp_text user "Author: Antmicro" (at -1.95 -12.364 270) (layer "B.Fab") hide
        (effects (font (size 0.7 0.7) (thickness 0.15)) (justify left bottom mirror))
    )
    (fp_line (start -10.999 -2.87) (end -10.999 1.481)
      (stroke (width 0.15) (type solid)) (layer "B.SilkS"))
    (fp_line (start -9.599 -4.12) (end -9.249 -4.12)
      (stroke (width 0.15) (type solid)) (layer "B.SilkS"))
    (fp_line (start -9.599 -2.87) (end -10.999 -2.87)
      (stroke (width 0.15) (type solid)) (layer "B.SilkS"))
    (fp_line (start -9.599 -2.87) (end -9.599 -4.12)
      (stroke (width 0.15) (type solid)) (layer "B.SilkS"))
    (fp_line (start -3.75 -4.12) (end -1.75 -4.12)
      (stroke (width 0.15) (type solid)) (layer "B.SilkS"))
    (fp_line (start -3.499 3.88) (end -1.499 3.88)
      (stroke (width 0.15) (type solid)) (layer "B.SilkS"))
    (fp_line (start 9.251 -4.12) (end 9.601 -4.12)
      (stroke (width 0.15) (type solid)) (layer "B.SilkS"))
    (fp_line (start 9.601 -4.12) (end 9.601 -2.87)
      (stroke (width 0.15) (type solid)) (layer "B.SilkS"))
    (fp_line (start 10.999 -2.87) (end 9.601 -2.87)
      (stroke (width 0.15) (type solid)) (layer "B.SilkS"))
    (fp_line (start 10.999 1.481) (end 10.999 -2.87)
      (stroke (width 0.15) (type solid)) (layer "B.SilkS"))
    (fp_line (start -11.2 -3.07) (end -9.8 -3.07)
      (stroke (width 0.05) (type solid)) (layer "B.CrtYd"))
    (fp_line (start -11.2 4.76) (end -11.2 -3.07)
      (stroke (width 0.05) (type solid)) (layer "B.CrtYd"))
    (fp_line (start -9.8 -4.8) (end 9.85 -4.8)
      (stroke (width 0.05) (type solid)) (layer "B.CrtYd"))
    (fp_line (start -9.8 -3.07) (end -9.8 -4.8)
      (stroke (width 0.05) (type solid)) (layer "B.CrtYd"))
    (fp_line (start 9.85 -4.8) (end 9.85 -3.07)
      (stroke (width 0.05) (type solid)) (layer "B.CrtYd"))
    (fp_line (start 9.85 -3.07) (end 11.2 -3.07)
      (stroke (width 0.05) (type solid)) (layer "B.CrtYd"))
    (fp_line (start 11.2 -3.07) (end 11.2 4.76)
      (stroke (width 0.05) (type solid)) (layer "B.CrtYd"))
    (fp_line (start 11.2 4.76) (end -11.2 4.76)
      (stroke (width 0.05) (type solid)) (layer "B.CrtYd"))
    (fp_line (start -10 0.251) (end 9.998 0.251)
      (stroke (width 0.15) (type solid)) (layer "B.Fab"))
    (pad "" np_thru_hole circle (at -10 -1.498 90) (size 1.15 1.15) (drill 1.15) (layers "*.Cu" "*.Mask"))
    (pad "" np_thru_hole circle (at 9.998 -1.498 90) (size 1.6 1.6) (drill 1.6) (layers "*.Cu" "*.Mask"))
    (pad "1" smd rect (at -9.25 3.75 90) (size 0.3 1.55) (layers "B.Cu" "B.Paste" "B.Mask")
      (net 1 "GND") (pinfunction "GND") (pintype "power_in"))
    (pad "2" smd rect (at -9.002 -3.749 90) (size 0.3 1.55) (layers "B.Cu" "B.Paste" "B.Mask")
      (net 15 "PS_3V3") (pinfunction "3.3V") (pintype "power_in"))
    (pad "3" smd rect (at -8.752 3.75 90) (size 0.3 1.55) (layers "B.Cu" "B.Paste" "B.Mask")
      (net 361 "/PCIE M2 key E /M2_USB_P") (pinfunction "USB_D+") (pintype "bidirectional"))
    (pad "4" smd rect (at -8.502 -3.749 90) (size 0.3 1.55) (layers "B.Cu" "B.Paste" "B.Mask")
      (net 15 "PS_3V3") (pinfunction "3.3V") (pintype "passive"))
    (pad "5" smd rect (at -8.252 3.75 90) (size 0.3 1.55) (layers "B.Cu" "B.Paste" "B.Mask")
      (net 360 "/PCIE M2 key E /M2_USB_N") (pinfunction "USB_D-") (pintype "bidirectional"))
    (pad "6" smd rect (at -8.001 -3.749 90) (size 0.3 1.55) (layers "B.Cu" "B.Paste" "B.Mask")
      (net 369 "unconnected-(J12-~{LED_1}-Pad6)") (pinfunction "~{LED_1}") (pintype "output+no_connect"))
    (pad "7" smd rect (at -7.751 3.75 90) (size 0.3 1.55) (layers "B.Cu" "B.Paste" "B.Mask")
      (net 1 "GND") (pinfunction "GND") (pintype "passive"))
    (pad "8" smd rect (at -7.501 -3.749 90) (size 0.3 1.55) (layers "B.Cu" "B.Paste" "B.Mask")
      (net 370 "unconnected-(J12-PCM_CLK-Pad8)") (pinfunction "PCM_CLK") (pintype "bidirectional+no_connect"))
    (pad "9" smd rect (at -7.251 3.75 90) (size 0.3 1.55) (layers "B.Cu" "B.Paste" "B.Mask")
      (net 371 "unconnected-(J12-SDIO_CLK-Pad9)") (pinfunction "SDIO_CLK") (pintype "input+no_connect"))
    (pad "10" smd rect (at -7.001 -3.749 90) (size 0.3 1.55) (layers "B.Cu" "B.Paste" "B.Mask")
      (net 372 "unconnected-(J12-PCM_SYNC-Pad10)") (pinfunction "PCM_SYNC") (pintype "bidirectional+no_connect"))
    (pad "11" smd rect (at -6.751 3.75 90) (size 0.3 1.55) (layers "B.Cu" "B.Paste" "B.Mask")
      (net 373 "unconnected-(J12-SDIO_CMD-Pad11)") (pinfunction "SDIO_CMD") (pintype "bidirectional+no_connect"))
    (pad "12" smd rect (at -6.501 -3.749 90) (size 0.3 1.55) (layers "B.Cu" "B.Paste" "B.Mask")
      (net 374 "unconnected-(J12-PCM_OUT-Pad12)") (pinfunction "PCM_OUT") (pintype "bidirectional+no_connect"))
    (pad "13" smd rect (at -6.251 3.75 90) (size 0.3 1.55) (layers "B.Cu" "B.Paste" "B.Mask")
      (net 375 "unconnected-(J12-SDIO_D0-Pad13)") (pinfunction "SDIO_D0") (pintype "bidirectional+no_connect"))
    (pad "14" smd rect (at -6.001 -3.749 90) (size 0.3 1.55) (layers "B.Cu" "B.Paste" "B.Mask")
      (net 376 "unconnected-(J12-PCM_IN-Pad14)") (pinfunction "PCM_IN") (pintype "bidirectional+no_connect"))
    (pad "15" smd rect (at -5.751 3.75 90) (size 0.3 1.55) (layers "B.Cu" "B.Paste" "B.Mask")
      (net 377 "unconnected-(J12-SDIO_D1-Pad15)") (pinfunction "SDIO_D1") (pintype "bidirectional+no_connect"))
    (pad "16" smd rect (at -5.501 -3.749 90) (size 0.3 1.55) (layers "B.Cu" "B.Paste" "B.Mask")
      (net 378 "unconnected-(J12-~{LED_2}-Pad16)") (pinfunction "~{LED_2}") (pintype "output+no_connect"))
    (pad "17" smd rect (at -5.251 3.75 90) (size 0.3 1.55) (layers "B.Cu" "B.Paste" "B.Mask")
      (net 379 "unconnected-(J12-SDIO_D2-Pad17)") (pinfunction "SDIO_D2") (pintype "bidirectional+no_connect"))
    (pad "18" smd rect (at -5.002 -3.749 90) (size 0.3 1.55) (layers "B.Cu" "B.Paste" "B.Mask")
      (net 1 "GND") (pinfunction "GND") (pintype "passive"))
    (pad "19" smd rect (at -4.752 3.75 90) (size 0.3 1.55) (layers "B.Cu" "B.Paste" "B.Mask")
      (net 381 "unconnected-(J12-SDIO_D3-Pad19)") (pinfunction "SDIO_D3") (pintype "bidirectional+no_connect"))
    (pad "20" smd rect (at -4.502 -3.749 90) (size 0.3 1.55) (layers "B.Cu" "B.Paste" "B.Mask")
      (net 382 "unconnected-(J12-~{UART_WAKE}-Pad20)") (pinfunction "~{UART_WAKE}") (pintype "output+no_connect"))
    (pad "21" smd rect (at -4.252 3.75 90) (size 0.3 1.55) (layers "B.Cu" "B.Paste" "B.Mask")
      (net 383 "unconnected-(J12-SDIO_~{WAKE}-Pad21)") (pinfunction "SDIO_~{WAKE}") (pintype "bidirectional+no_connect"))
    (pad "22" smd rect (at -4.002 -3.749 90) (size 0.3 1.55) (layers "B.Cu" "B.Paste" "B.Mask")
      (net 384 "unconnected-(J12-UART_TXD-Pad22)") (pinfunction "UART_TXD") (pintype "bidirectional+no_connect"))
    (pad "23" smd rect (at -3.751 3.75 90) (size 0.3 1.55) (layers "B.Cu" "B.Paste" "B.Mask")
      (net 385 "unconnected-(J12-SDIO_~{RESET}-Pad23)") (pinfunction "SDIO_~{RESET}") (pintype "input+no_connect"))
    (pad "32" smd rect (at -1.501 -3.749 90) (size 0.3 1.55) (layers "B.Cu" "B.Paste" "B.Mask")
      (net 386 "unconnected-(J12-UART_RXD-Pad32)") (pinfunction "UART_RXD") (pintype "bidirectional+no_connect"))
    (pad "33" smd rect (at -1.251 3.75 90) (size 0.3 1.55) (layers "B.Cu" "B.Paste" "B.Mask")
      (net 1 "GND") (pinfunction "GND") (pintype "passive"))
    (pad "34" smd rect (at -1.001 -3.749 90) (size 0.3 1.55) (layers "B.Cu" "B.Paste" "B.Mask")
      (net 387 "unconnected-(J12-UART_RTS-Pad34)") (pinfunction "UART_RTS") (pintype "bidirectional+no_connect"))
    (pad "35" smd rect (at -0.751 3.75 90) (size 0.3 1.55) (layers "B.Cu" "B.Paste" "B.Mask")
      (net 89 "/PCIE M2 key E /GTR_DP3_M2C_C_P") (pinfunction "PET0+") (pintype "input"))
    (pad "36" smd rect (at -0.501 -3.749 90) (size 0.3 1.55) (layers "B.Cu" "B.Paste" "B.Mask")
      (net 388 "unconnected-(J12-UART_CTS-Pad36)") (pinfunction "UART_CTS") (pintype "bidirectional+no_connect"))
    (pad "37" smd rect (at -0.251 3.75 90) (size 0.3 1.55) (layers "B.Cu" "B.Paste" "B.Mask")
      (net 91 "/PCIE M2 key E /GTR_DP3_M2C_C_N") (pinfunction "PET0-") (pintype "input"))
    (pad "38" smd rect (at -0.001 -3.749 90) (size 0.3 1.55) (layers "B.Cu" "B.Paste" "B.Mask")
      (net 389 "unconnected-(J12-VENDOR_1-Pad38)") (pinfunction "VENDOR_1") (pintype "bidirectional+no_connect"))
    (pad "39" smd rect (at 0.249 3.75 90) (size 0.3 1.55) (layers "B.Cu" "B.Paste" "B.Mask")
      (net 1 "GND") (pinfunction "GND") (pintype "passive"))
    (pad "40" smd rect (at 0.499 -3.749 90) (size 0.3 1.55) (layers "B.Cu" "B.Paste" "B.Mask")
      (net 390 "unconnected-(J12-VENDOR_2-Pad40)") (pinfunction "VENDOR_2") (pintype "bidirectional+no_connect"))
    (pad "41" smd rect (at 0.749 3.75 90) (size 0.3 1.55) (layers "B.Cu" "B.Paste" "B.Mask")
      (net 119 "/PCIE M2 key E /GTR_DP3_C2M_P") (pinfunction "PER0+") (pintype "output"))
    (pad "42" smd rect (at 0.999 -3.749 90) (size 0.3 1.55) (layers "B.Cu" "B.Paste" "B.Mask")
      (net 391 "unconnected-(J12-VENDOR_3-Pad42)") (pinfunction "VENDOR_3") (pintype "bidirectional+no_connect"))
    (pad "43" smd rect (at 1.249 3.75 90) (size 0.3 1.55) (layers "B.Cu" "B.Paste" "B.Mask")
      (net 120 "/PCIE M2 key E /GTR_DP3_C2M_N") (pinfunction "PER0-") (pintype "output"))
    (pad "44" smd rect (at 1.499 -3.749 90) (size 0.3 1.55) (layers "B.Cu" "B.Paste" "B.Mask")
      (net 392 "unconnected-(J12-COEX3-Pad44)") (pinfunction "COEX3") (pintype "bidirectional+no_connect"))
    (pad "45" smd rect (at 1.749 3.75 90) (size 0.3 1.55) (layers "B.Cu" "B.Paste" "B.Mask")
      (net 1 "GND") (pinfunction "GND") (pintype "passive"))
    (pad "46" smd rect (at 1.999 -3.749 90) (size 0.3 1.55) (layers "B.Cu" "B.Paste" "B.Mask")
      (net 393 "unconnected-(J12-COEX_TXD-Pad46)") (pinfunction "COEX_TXD") (pintype "bidirectional+no_connect"))
    (pad "47" smd rect (at 2.249 3.75 90) (size 0.3 1.55) (layers "B.Cu" "B.Paste" "B.Mask")
      (net 122 "/Clock distribution/GTR_REFCLK3_P") (pinfunction "REFCLK0+") (pintype "input"))
    (pad "48" smd rect (at 2.499 -3.749 90) (size 0.3 1.55) (layers "B.Cu" "B.Paste" "B.Mask")
      (net 394 "unconnected-(J12-COEX_RXD-Pad48)") (pinfunction "COEX_RXD") (pintype "bidirectional+no_connect"))
    (pad "49" smd rect (at 2.749 3.75 90) (size 0.3 1.55) (layers "B.Cu" "B.Paste" "B.Mask")
      (net 121 "/Clock distribution/GTR_REFCLK3_N") (pinfunction "REFCLK0-") (pintype "input"))
    (pad "50" smd rect (at 2.999 -3.749 90) (size 0.3 1.55) (layers "B.Cu" "B.Paste" "B.Mask")
      (net 395 "unconnected-(J12-SUSCLK-Pad50)") (pinfunction "SUSCLK") (pintype "input+no_connect"))
    (pad "51" smd rect (at 3.249 3.75 90) (size 0.3 1.55) (layers "B.Cu" "B.Paste" "B.Mask")
      (net 1 "GND") (pinfunction "GND") (pintype "passive"))
    (pad "52" smd rect (at 3.499 -3.749 90) (size 0.3 1.55) (layers "B.Cu" "B.Paste" "B.Mask")
      (net 221 "/PCIE M2 key E /~{M2_PERST}") (pinfunction "~{PERST0}") (pintype "input"))
    (pad "53" smd rect (at 3.749 3.75 90) (size 0.3 1.55) (layers "B.Cu" "B.Paste" "B.Mask")
      (net 396 "Net-(J12-~{CLKREQ0})") (pinfunction "~{CLKREQ0}") (pintype "output"))
    (pad "54" smd rect (at 3.999 -3.749 90) (size 0.3 1.55) (layers "B.Cu" "B.Paste" "B.Mask")
      (net 397 "unconnected-(J12-W_DISABLE2-Pad54)") (pinfunction "W_DISABLE2") (pintype "input+no_connect"))
    (pad "55" smd rect (at 4.249 3.75 90) (size 0.3 1.55) (layers "B.Cu" "B.Paste" "B.Mask")
      (net 227 "/PCIE M2 key E /~{M2_PEWAKE}") (pinfunction "~{PEWAKE0}") (pintype "output"))
    (pad "56" smd rect (at 4.499 -3.749 90) (size 0.3 1.55) (layers "B.Cu" "B.Paste" "B.Mask")
      (net 398 "unconnected-(J12-W_DISABLE1-Pad56)") (pinfunction "W_DISABLE1") (pintype "input+no_connect"))
    (pad "57" smd rect (at 4.749 3.75 90) (size 0.3 1.55) (layers "B.Cu" "B.Paste" "B.Mask")
      (net 1 "GND") (pinfunction "GND") (pintype "passive"))
    (pad "58" smd rect (at 4.999 -3.749 90) (size 0.3 1.55) (layers "B.Cu" "B.Paste" "B.Mask")
      (net 399 "unconnected-(J12-I2C_DATA-Pad58)") (pinfunction "I2C_DATA") (pintype "bidirectional+no_connect"))
    (pad "59" smd rect (at 5.249 3.75 90) (size 0.3 1.55) (layers "B.Cu" "B.Paste" "B.Mask")
      (net 400 "unconnected-(J12-PET1+-Pad59)") (pinfunction "PET1+") (pintype "input+no_connect"))
    (pad "60" smd rect (at 5.499 -3.749 90) (size 0.3 1.55) (layers "B.Cu" "B.Paste" "B.Mask")
      (net 401 "unconnected-(J12-I2C_CLK-Pad60)") (pinfunction "I2C_CLK") (pintype "bidirectional+no_connect"))
    (pad "61" smd rect (at 5.749 3.75 90) (size 0.3 1.55) (layers "B.Cu" "B.Paste" "B.Mask")
      (net 402 "unconnected-(J12-PET1--Pad61)") (pinfunction "PET1-") (pintype "input+no_connect"))
    (pad "62" smd rect (at 5.999 -3.749 90) (size 0.3 1.55) (layers "B.Cu" "B.Paste" "B.Mask")
      (net 403 "unconnected-(J12-~{ALERT}-Pad62)") (pinfunction "~{ALERT}") (pintype "output+no_connect"))
    (pad "63" smd rect (at 6.249 3.75 90) (size 0.3 1.55) (layers "B.Cu" "B.Paste" "B.Mask")
      (net 1 "GND") (pinfunction "GND") (pintype "passive"))
    (pad "64" smd rect (at 6.499 -3.749 90) (size 0.3 1.55) (layers "B.Cu" "B.Paste" "B.Mask")
      (net 404 "unconnected-(J12-RFU-Pad64)") (pinfunction "RFU") (pintype "no_connect"))
    (pad "65" smd rect (at 6.749 3.75 90) (size 0.3 1.55) (layers "B.Cu" "B.Paste" "B.Mask")
      (net 405 "unconnected-(J12-PER1+-Pad65)") (pinfunction "PER1+") (pintype "output+no_connect"))
    (pad "66" smd rect (at 6.998 -3.749 90) (size 0.3 1.55) (layers "B.Cu" "B.Paste" "B.Mask")
      (net 406 "unconnected-(J12-UIM_SWP-Pad66)") (pinfunction "UIM_SWP") (pintype "bidirectional+no_connect"))
    (pad "67" smd rect (at 7.248 3.75 90) (size 0.3 1.55) (layers "B.Cu" "B.Paste" "B.Mask")
      (net 407 "unconnected-(J12-PER1--Pad67)") (pinfunction "PER1-") (pintype "output+no_connect"))
    (pad "68" smd rect (at 7.498 -3.749 90) (size 0.3 1.55) (layers "B.Cu" "B.Paste" "B.Mask")
      (net 408 "unconnected-(J12-UIM_POWER_SNK-Pad68)") (pinfunction "UIM_POWER_SNK") (pintype "bidirectional+no_connect"))
    (pad "69" smd rect (at 7.748 3.75 90) (size 0.3 1.55) (layers "B.Cu" "B.Paste" "B.Mask")
      (net 1 "GND") (pinfunction "GND") (pintype "passive"))
    (pad "70" smd rect (at 7.998 -3.749 90) (size 0.3 1.55) (layers "B.Cu" "B.Paste" "B.Mask")
      (net 411 "unconnected-(J12-UIM_POWER_SRC-Pad70)") (pinfunction "UIM_POWER_SRC") (pintype "bidirectional+no_connect"))
    (pad "71" smd rect (at 8.248 3.75 90) (size 0.3 1.55) (layers "B.Cu" "B.Paste" "B.Mask")
      (net 412 "unconnected-(J12-REFCLK1+-Pad71)") (pinfunction "REFCLK1+") (pintype "input+no_connect"))
    (pad "72" smd rect (at 8.498 -3.749 90) (size 0.3 1.55) (layers "B.Cu" "B.Paste" "B.Mask")
      (net 15 "PS_3V3") (pinfunction "3.3V") (pintype "passive"))
    (pad "73" smd rect (at 8.748 3.75 90) (size 0.3 1.55) (layers "B.Cu" "B.Paste" "B.Mask")
      (net 413 "unconnected-(J12-REFCLK1--Pad73)") (pinfunction "REFCLK1-") (pintype "input+no_connect"))
    (pad "74" smd rect (at 8.998 -3.749 90) (size 0.3 1.55) (layers "B.Cu" "B.Paste" "B.Mask")
      (net 15 "PS_3V3") (pinfunction "3.3V") (pintype "passive"))
    (pad "75" smd rect (at 9.248 3.75 90) (size 0.3 1.55) (layers "B.Cu" "B.Paste" "B.Mask")
      (net 1 "GND") (pinfunction "GND") (pintype "passive"))
    (pad "MP" smd rect (at -10.351 3.002 90) (size 1.2 2.75) (layers "B.Cu" "B.Paste" "B.Mask")
      (net 1 "GND") (pinfunction "MP") (pintype "passive"))
    (pad "MP" smd rect (at 10.35 3.002 90) (size 1.2 2.75) (layers "B.Cu" "B.Paste" "B.Mask")
      (net 1 "GND") (pinfunction "MP") (pintype "passive"))
  )
)
